FILE_TYPE = MULTI_PHYS_TABLE;
PART 'SCONN64_H87568002_A'
{======================================================================================================================================================================================}
:PACK_TYPE | MATERIAL | PART_NUMBER     = EnvComp | PART_NUMBER  | JEDEC_TYPE            | CLASS | DESCRIPTION                                                         | HEIGHT     | COMPONENT_TYPE | LPID   | SPEED_URL | Status |RPL| AML | Bus_Unit | Days ;
{======================================================================================================================================================================================}
'SMT'      | 'CONN'   | 'H87568-002'(!) = ''      | 'H87568-002' | 'SCONN64_H87568002_A' | 'IO'  | '(GENERIC IO USE SYM_1)CONN,MISC,7.7MM,64P,BERG,RCPT,0.8,VT,SMT'    | '0.315 IN' | 'SMTCONN'      | '4203' | 'http://speed.intel.com:8081/speed/module/pdm/item/pdm_item_detail_direct.asp?item_cde=H87568-002&item_rev=01&url_param=unused' | '' | '' | '' | '' | '' 
'SMT'      | 'EMPTY'  | 'H87568-002'(!) = ''      | 'H87568-002' | 'SCONN64_H87568002_A' | 'IO'  | '(GENERIC IO USE SYM_1)CONN,MISC,7.7MM,64P,BERG,RCPT,0.8,VT,SMT'    | '0.315 IN' | 'SMTCONN'      | '4203' | 'http://speed.intel.com:8081/speed/module/pdm/item/pdm_item_detail_direct.asp?item_cde=H87568-002&item_rev=01&url_param=unused' | '' | '' | '' | '' | '' 
'SMT1'     | 'CONN'   | 'H87568-002'(!) = ''      | 'H87568-002' | 'SCONN64_H87568002_A' | 'IO'  | '(LOGICAL PART USE SYM_2)CONN,MISC,7.7MM,64P,BERG,RCPT,0.8,VT,SMT'  | '0.315 IN' | 'SMTCONN'      | '4203' | 'http://speed.intel.com:8081/speed/module/pdm/item/pdm_item_detail_direct.asp?item_cde=H87568-002&item_rev=01&url_param=unused' | '' | '' | '' | '' | '' 
'SMT1'     | 'EMPTY'  | 'H87568-002'(!) = ''      | 'H87568-002' | 'SCONN64_H87568002_A' | 'IO'  | '(LOGICAL PART USE SYM_2)CONN,MISC,7.7MM,64P,BERG,RCPT,0.8,VT,SMT'  | '0.315 IN' | 'SMTCONN'      | '4203' | 'http://speed.intel.com:8081/speed/module/pdm/item/pdm_item_detail_direct.asp?item_cde=H87568-002&item_rev=01&url_param=unused' | '' | '' | '' | '' | '' 
END_PART
END.
